FILE_TYPE = CONNECTIVITY;
{Allegro Design Entry HDL 17.2-2016 S081 (4005846) 1/11/2022}
"PAGE_NUMBER" = 149;
0"NC";
1"GND\g";
2"GND\g";
3"GND\g";
4"GND\g";
5"GND\g";
6"GND\g";
7"PVDD18_S5_P0\g";
8"GND\g";
9"GND\g";
10"GND\g";
11"GND\g";
12"GND\g";
13"GND\g";
14"GND\g";
15"GND\g";
16"GND\g";
17"PVDD18_S5_P0\g";
18"GND\g";
19"GND\g";
20"P3V3_STBY\g";
21"GND\g";
22"JTAG_BMC_OE_N";
23"HDT_HDR_RESET_N";
24"HDT_HDR_TCK";
25"HDT_HDR_TMS";
26"HDT_HDR_TDI";
27"JTAG_BMC_R_D_OE";
28"P3V3_STBY\g";
29"PVDD18_S5_P0\g";
30"PVDD18_S5_P0\g";
31"GND\g";
32"PVDD18_S5_P0\g";
33"PVDD18_S5_P0\g";
34"GND\g";
35"PVDD18_S5_P0\g";
36"P3V3_STBY\g";
37"GND\g";
38"PVDD18_S5_P0\g";
39"PVDD18_S5_P0\g";
40"GND\g";
41"GND\g";
42"JTAG_BMC_OE";
43"HDT_HDR_TDI";
44"HDT_HDR_TDO";
45"JTAG_SCM_MUX_TDO";
46"JTAG_SCM_MUX_TDI";
47"JTAG_TDO";
48"JTAG_TDI_R";
49"JTAG_TDI";
50"HDT_HDR_TRST_N";
51"CPU0_XTRIG_L6";
52"CPU0_XTRIG_L7";
53"CPU0_XTRIG_L5";
54"PRSNT_HDT_N";
55"PRSNT_HDT_R_N";
56"HDT_CPU0_XTRIG_L6";
57"HDT_CPU0_XTRIG_L7";
58"HDT_CPU0_XTRIG_L5";
59"HDT_HDR_TRST_N_R";
60"HDT_HDR_R_TCK";
61"HDT_HDR_R_TMS";
62"HDT_HDR_R_TDI";
63"HDT_HDR_PWROK";
64"HDT_HDR_TCK";
65"HDT_HDR_TRST_N";
66"HDT_HDR_TMS";
67"HDT_HDR_DBREQ_N";
68"JTAG_SCM_MUX_TCK";
69"JTAG_SCM_MUX_TMS";
70"JTAG_SCM_TRST_N";
71"JTAG_SCM_DBREQ_N";
72"JTAG_DBREQ_R_N";
73"JTAG_DBREQ_N";
74"JTAG_TCK_R";
75"JTAG_TRST_R_N";
76"JTAG_TMS_R";
77"HDT_CPU0_HDT_CONN_TESTEN";
78"HDT_HDR_DBREQ_R_N";
79"HDT_HDR_DBREQ_N";
80"CPU0_HDT_CONN_TESTEN";
81"HDT_HDR_TDO";
82"JTAG_TCK";
83"JTAG_TMS";
84"JTAG_TRST_N";
%"SN74AVC2T245RSWR"
"1","(-7000,2100)","2","pure_quanta","I1";
;
LOCATION"U147"
$SEC"1"
CDS_SEC"1"
PART_TYPE"SMLF"
MATERIAL"IC"
VALUE"SN74AVC2T245RSWR"
PART_NUMBER"AL02T245000"
CDS_LMAN_SYM_OUTLINE"-250,375,250,-375"
CDS_LIB"pure_quanta"
NEEDS_NO_SIZE"TRUE";
"DIR1"
$PN"10"28;
"A2"
$PN"9"46;
"A1"
$PN"8"45;
"VCCA"
$PN"7"28;
"VCCB"
$PN"6"39;
"B1"
$PN"5"48;
"B2"
$PN"4"47;
"GND"
$PN"3"41;
"OE_# \B"
$PN"2"22;
"DIR2"
$PN"1"41;
%"Q_CAP"
"1","(-2650,4550)","0","pure_quanta","I10";
;
LOCATION"C1509"
$SEC"1"
CDS_SEC"1"
MATERIAL"X7R"
TOLERANCE"10%"
VALUE"0.1UF"
PART_NUMBER"CH4103K1B08"
VOLTAGE"16V"
PACK_TYPE"C0402"
CDS_LIB"pure_quanta";
"B"
$PN"2"1;
"A"
$PN"1"30;
%"Q_RES"
"2","(-6425,3550)","0","pure_quanta","I101";
;
LOCATION"R617"
$SEC"1"
CDS_SEC"1"
WATTAGE"1/16W"
MATERIAL"CHIP"
TOLERANCE"5%"
VALUE"4.7K"
PART_NUMBER"TMP_QCS24702JB38"
PACK_TYPE"0402LF"
CDS_LIB"pure_quanta";
"A"
$PN"1"17;
"B"
$PN"2"27;
%"MOSFET_N"
"1","(-7525,700)","0","pure_quanta","I102";
;
LOCATION"Q62"
$SEC"1"
CDS_SEC"1"
MATERIAL"IC"
VALUE"BSS138K"
PART_NUMBER"BAM138K0000"
PART_TYPE"SMLF"
MANUF_PN"BSS138K"
CDS_LIB"pure_quanta"
CDS_LMAN_SYM_OUTLINE"-50,50,100,-150"
PACK_TYPE"SMLF";
"GATE"
$PN"G"42;
"SOURCE"
$PN"S"21;
"DRAIN"
$PN"D"22;
%"Q_RES"
"1","(-3975,5850)","0","pure_quanta","I109";
;
LOCATION"R1354"
$SEC"1"
CDS_SEC"1"
VALUE"0"
CDS_LIB"pure_quanta"
WATTAGE"1/16W"
MATERIAL"CHIP"
TOLERANCE"5%"
PART_NUMBER"CS00002JB38"
PACK_TYPE"0402LF";
"B"
$PN"2"26;
"A"
$PN"1"62;
%"GND"
"1","(-2650,4375)","0","pure_quanta_power","I11";
;
CDS_LIB"pure_quanta_power"
SIZE"1B"
HDL_POWER"GND";
"A<SIZE-1..0>\NAC"1;
%"GND"
"1","(-3675,5100)","0","pure_quanta_power","I110";
;
SIZE"1B"
CDS_LIB"pure_quanta_power"
HDL_POWER"GND";
"A<SIZE-1..0>\NAC"2;
%"Q_RES"
"2","(-3650,6125)","0","pure_quanta","I111";
;
LOCATION"R1624"
$SEC"1"
CDS_SEC"1"
TOLERANCE"5%"
VALUE"1K"
CDS_LIB"pure_quanta"
WATTAGE"1/16W"
MATERIAL"CHIP"
PART_NUMBER"TMP_QCS21002JB34"
PACK_TYPE"0402LF";
"A"
$PN"1"29;
"B"
$PN"2"24;
%"Q_RES"
"2","(-3675,5325)","0","pure_quanta","I112";
;
LOCATION"R1629"
$SEC"1"
CDS_SEC"1"
WATTAGE"1/16W"
MATERIAL"CHIP"
TOLERANCE"5%"
VALUE"1K"
PART_NUMBER"TMP_QCS21002JB34"
PACK_TYPE"0402LF"
CDS_LIB"pure_quanta";
"A"
$PN"1"77;
"B"
$PN"2"2;
%"Q_RES"
"1","(-3025,5600)","0","pure_quanta","I113";
;
LOCATION"R1631"
$SEC"1"
CDS_SEC"1"
VALUE"33"
CDS_LIB"pure_quanta"
WATTAGE"1/16W"
MATERIAL"CHIP"
TOLERANCE"5%"
PART_NUMBER"CS03302JB29"
PACK_TYPE"0402LF";
"B"
$PN"2"79;
"A"
$PN"1"78;
%"Q_RES"
"1","(-3025,5550)","0","pure_quanta","I114";
;
LOCATION"R1632"
$SEC"1"
CDS_SEC"1"
VALUE"33"
CDS_LIB"pure_quanta"
WATTAGE"1/16W"
MATERIAL"CHIP"
TOLERANCE"5%"
PART_NUMBER"CS03302JB29"
PACK_TYPE"0402LF";
"B"
$PN"2"80;
"A"
$PN"1"77;
%"Q_RES"
"2","(-3525,6125)","0","pure_quanta","I115";
;
LOCATION"R1626"
$SEC"1"
CDS_SEC"1"
TOLERANCE"5%"
VALUE"1K"
CDS_LIB"pure_quanta"
WATTAGE"1/16W"
MATERIAL"CHIP"
PART_NUMBER"TMP_QCS21002JB34"
PACK_TYPE"0402LF";
"A"
$PN"1"29;
"B"
$PN"2"25;
%"Q_RES"
"2","(-3400,6125)","0","pure_quanta","I116";
;
LOCATION"R1627"
$SEC"1"
CDS_SEC"1"
VALUE"1K"
TOLERANCE"5%"
CDS_LIB"pure_quanta"
WATTAGE"1/16W"
MATERIAL"CHIP"
PART_NUMBER"TMP_QCS21002JB34"
PACK_TYPE"0402LF";
"A"
$PN"1"29;
"B"
$PN"2"26;
%"Q_RES"
"2","(-3275,6125)","0","pure_quanta","I117";
;
LOCATION"R1628"
$SEC"1"
CDS_SEC"1"
TOLERANCE"5%"
VALUE"1K"
CDS_LIB"pure_quanta"
WATTAGE"1/16W"
MATERIAL"CHIP"
PART_NUMBER"TMP_QCS21002JB34"
PACK_TYPE"0402LF";
"A"
$PN"1"29;
"B"
$PN"2"81;
%"Q_RES"
"2","(-3150,6125)","0","pure_quanta","I118";
;
LOCATION"R1630"
$SEC"1"
CDS_SEC"1"
TOLERANCE"5%"
VALUE"1K"
CDS_LIB"pure_quanta"
WATTAGE"1/16W"
MATERIAL"CHIP"
PART_NUMBER"TMP_QCS21002JB34"
PACK_TYPE"0402LF";
"A"
$PN"1"29;
"B"
$PN"2"78;
%"UNIVERSAL_POWER"
"1","(-3650,6400)","0","pure_quanta_power","I119";
;
HDL_POWER"PVDD18_S5_P0"
CDS_LIB"pure_quanta_power";
"A"29;
%"UNIVERSAL_POWER"
"1","(-2725,4850)","0","pure_quanta_power","I12";
;
HDL_POWER"PVDD18_S5_P0"
CDS_LIB"pure_quanta_power";
"A"30;
%"GND"
"1","(-2350,5100)","0","pure_quanta_power","I120";
;
SIZE"1B"
CDS_LIB"pure_quanta_power"
HDL_POWER"GND";
"A<SIZE-1..0>\NAC"3;
%"GND"
"1","(-2125,5100)","0","pure_quanta_power","I121";
;
CDS_LIB"pure_quanta_power"
SIZE"1B"
HDL_POWER"GND";
"A<SIZE-1..0>\NAC"4;
%"Q_CAP"
"1","(-2125,5325)","0","pure_quanta","I123";
;
LOCATION"C551"
$SEC"1"
CDS_SEC"1"
MATERIAL"X7R"
TOLERANCE"10%"
VALUE"0.01UF"
VOLTAGE"50V"
PACK_TYPE"C0402"
SIGNAL_MODEL"DEFAULT_CAPACITOR_10000PF_2_1"
CDS_LIB"pure_quanta"
PART_NUMBER"CH31006KB18"
ROOM"BMCLESS";
"B"
$PN"2"4;
"A"
$PN"1"80;
%"Q_RES"
"1","(-3975,5950)","0","pure_quanta","I132";
;
LOCATION"R1352"
$SEC"1"
CDS_SEC"1"
VALUE"0"
CDS_LIB"pure_quanta"
WATTAGE"1/16W"
MATERIAL"CHIP"
TOLERANCE"5%"
PART_NUMBER"CS00002JB38"
PACK_TYPE"0402LF";
"B"
$PN"2"24;
"A"
$PN"1"60;
%"Q_RES"
"1","(-3975,5900)","0","pure_quanta","I133";
;
LOCATION"R1353"
$SEC"1"
CDS_SEC"1"
VALUE"0"
CDS_LIB"pure_quanta"
WATTAGE"1/16W"
MATERIAL"CHIP"
TOLERANCE"5%"
PART_NUMBER"CS00002JB38"
PACK_TYPE"0402LF";
"B"
$PN"2"25;
"A"
$PN"1"61;
%"Q_CAP"
"1","(-2350,5325)","0","pure_quanta","I134";
;
LOCATION"C87"
$SEC"1"
CDS_SEC"1"
MATERIAL"X7R"
TOLERANCE"10%"
VALUE"0.001UF"
VOLTAGE"50V"
PACK_TYPE"C0402"
CDS_LIB"pure_quanta"
PART_NUMBER"CH30106KB19";
"B"
$PN"2"3;
"A"
$PN"1"79;
%"Q_CAP"
"1","(-2575,5325)","0","pure_quanta","I137";
;
LOCATION"C605"
$SEC"1"
CDS_SEC"1"
MATERIAL"X7R"
TOLERANCE"10%"
VALUE"0.001UF"
VOLTAGE"50V"
PACK_TYPE"C0402"
CDS_LIB"pure_quanta"
PART_NUMBER"CH30106KB19";
"B"
$PN"2"5;
"A"
$PN"1"26;
%"GND"
"1","(-2575,5100)","0","pure_quanta_power","I138";
;
SIZE"1B"
CDS_LIB"pure_quanta_power"
HDL_POWER"GND";
"A<SIZE-1..0>\NAC"5;
%"Q_CAP"
"1","(-2800,5325)","0","pure_quanta","I140";
;
LOCATION"C604"
$SEC"1"
CDS_SEC"1"
MATERIAL"X7R"
TOLERANCE"10%"
VALUE"0.001UF"
VOLTAGE"50V"
PACK_TYPE"C0402"
CDS_LIB"pure_quanta"
PART_NUMBER"CH30106KB19";
"B"
$PN"2"6;
"A"
$PN"1"24;
%"GND"
"1","(-2800,5100)","0","pure_quanta_power","I141";
;
SIZE"1B"
CDS_LIB"pure_quanta_power"
HDL_POWER"GND";
"A<SIZE-1..0>\NAC"6;
%"SCONN20_HSU2101L00007H"
"1","(-5125,5725)","0","pure_quanta","I142";
;
LOCATION"J54"
$SEC"1"
CDS_SEC"1"
PART_TYPE"SMLF"
MATERIAL"IO"
VALUE"SCONN20_HSU2101-L0000-7H"
PART_NUMBER"DFHD20MS153"
CDS_LIB"pure_quanta"
NEEDS_NO_SIZE"TRUE"
CDS_LMAN_SYM_OUTLINE"-100,275,100,-275";
"20"
$PN"20"0;
"19"
$PN"19"32;
"18"
$PN"18"77;
"17"
$PN"17"31;
"16"
$PN"16"78;
"15"
$PN"15"58;
"14"
$PN"14"0;
"13"
$PN"13"57;
"12"
$PN"12"23;
"11"
$PN"11"56;
"10"
$PN"10"63;
"9"
$PN"9"59;
"8"
$PN"8"81;
"7"
$PN"7"31;
"6"
$PN"6"62;
"5"
$PN"5"31;
"4"
$PN"4"61;
"3"
$PN"3"55;
"2"
$PN"2"60;
"1"
$PN"1"32;
%"GND"
"1","(-5475,5350)","0","pure_quanta_power","I143";
;
CDS_LIB"pure_quanta_power"
SIZE"1B"
HDL_POWER"GND";
"A<SIZE-1..0>\NAC"31;
%"UNIVERSAL_POWER"
"1","(-5600,6200)","0","pure_quanta_power","I144";
;
HDL_POWER"PVDD18_S5_P0"
CDS_LIB"pure_quanta_power";
"A"32;
%"UNIVERSAL_POWER"
"1","(-6050,6450)","0","pure_quanta_power","I145";
;
HDL_POWER"PVDD18_S5_P0"
CDS_LIB"pure_quanta_power";
"A"7;
%"Q_RES"
"2","(-6050,6250)","0","pure_quanta","I146";
;
LOCATION"R1621"
$SEC"1"
CDS_SEC"1"
WATTAGE"1/16W"
MATERIAL"CHIP"
TOLERANCE"5%"
VALUE"1K"
PACK_TYPE"0402LF"
CDS_LIB"pure_quanta"
PART_NUMBER"TMP_QCS21002JB34";
"A"
$PN"1"7;
"B"
$PN"2"59;
%"Q_RES"
"1","(-6300,5650)","0","pure_quanta","I147";
;
LOCATION"R477"
$SEC"1"
CDS_SEC"1"
VALUE"33"
CDS_LIB"pure_quanta"
WATTAGE"1/16W"
MATERIAL"CHIP"
TOLERANCE"5%"
PART_NUMBER"CS03302JB29"
PACK_TYPE"0402LF";
"B"
$PN"2"57;
"A"
$PN"1"52;
%"Q_RES"
"1","(-6300,5700)","0","pure_quanta","I148";
;
LOCATION"R476"
$SEC"1"
CDS_SEC"1"
VALUE"33"
CDS_LIB"pure_quanta"
WATTAGE"1/16W"
MATERIAL"CHIP"
TOLERANCE"5%"
PART_NUMBER"CS03302JB29"
PACK_TYPE"0402LF";
"B"
$PN"2"56;
"A"
$PN"1"51;
%"Q_RES"
"1","(-6300,5750)","0","pure_quanta","I149";
;
LOCATION"R1620"
$SEC"1"
CDS_SEC"1"
VALUE"33"
CDS_LIB"pure_quanta"
WATTAGE"1/16W"
MATERIAL"CHIP"
TOLERANCE"5%"
PART_NUMBER"CS03302JB29"
PACK_TYPE"0402LF";
"B"
$PN"2"59;
"A"
$PN"1"50;
%"Q_RES"
"1","(-6300,5600)","0","pure_quanta","I150";
;
LOCATION"R478"
$SEC"1"
CDS_SEC"1"
VALUE"33"
CDS_LIB"pure_quanta"
WATTAGE"1/16W"
MATERIAL"CHIP"
TOLERANCE"5%"
PART_NUMBER"CS03302JB29"
PACK_TYPE"0402LF";
"B"
$PN"2"58;
"A"
$PN"1"53;
%"GND"
"1","(-7000,5150)","0","pure_quanta_power","I151";
;
SIZE"1B"
CDS_LIB"pure_quanta_power"
HDL_POWER"GND";
"A<SIZE-1..0>\NAC"8;
%"Q_CAP"
"1","(-7000,5375)","0","pure_quanta","I152";
;
LOCATION"C85"
$SEC"1"
CDS_SEC"1"
MATERIAL"X7R"
TOLERANCE"10%"
VALUE"0.001UF"
VOLTAGE"50V"
PACK_TYPE"C0402"
CDS_LIB"pure_quanta"
PART_NUMBER"CH30106KB19";
"B"
$PN"2"8;
"A"
$PN"1"50;
%"Q_RES"
"1","(-6300,5900)","0","pure_quanta","I157";
;
LOCATION"R1528"
$SEC"1"
CDS_SEC"1"
VALUE"33"
CDS_LIB"pure_quanta"
WATTAGE"1/16W"
MATERIAL"CHIP"
TOLERANCE"5%"
PART_NUMBER"CS03302JB29"
PACK_TYPE"0402LF";
"B"
$PN"2"55;
"A"
$PN"1"54;
%"UNIVERSAL_POWER"
"1","(-3750,4825)","0","pure_quanta_power","I20";
;
HDL_POWER"PVDD18_S5_P0"
CDS_LIB"pure_quanta_power";
"A"33;
%"Q_CAP"
"1","(-800,3775)","0","pure_quanta","I21";
;
LOCATION"C1512"
$SEC"1"
CDS_SEC"1"
MATERIAL"NPO"
TOLERANCE"5%"
VALUE"33PF"
PART_NUMBER"TMP_QCH03306JB04"
VOLTAGE"50V"
PACK_TYPE"0402"
CDS_LIB"pure_quanta";
"B"
$PN"2"9;
"A"
$PN"1"73;
%"GND"
"1","(-800,3450)","0","pure_quanta_power","I22";
;
CDS_LIB"pure_quanta_power"
SIZE"1B"
HDL_POWER"GND";
"A<SIZE-1..0>\NAC"9;
%"Q_CAP"
"1","(-1125,3775)","0","pure_quanta","I23";
;
LOCATION"C1511"
$SEC"1"
CDS_SEC"1"
MATERIAL"NPO"
TOLERANCE"5%"
VALUE"33PF"
VOLTAGE"50V"
PACK_TYPE"0402"
CDS_LIB"pure_quanta"
PART_NUMBER"TMP_QCH03306JB04";
"B"
$PN"2"10;
"A"
$PN"1"84;
%"GND"
"1","(-1125,3450)","0","pure_quanta_power","I24";
;
CDS_LIB"pure_quanta_power"
SIZE"1B"
HDL_POWER"GND";
"A<SIZE-1..0>\NAC"10;
%"Q_CAP"
"1","(-1500,3775)","0","pure_quanta","I25";
;
LOCATION"C1510"
$SEC"1"
CDS_SEC"1"
MATERIAL"NPO"
TOLERANCE"5%"
VALUE"33PF"
VOLTAGE"50V"
PACK_TYPE"0402"
CDS_LIB"pure_quanta"
PART_NUMBER"TMP_QCH03306JB04";
"B"
$PN"2"11;
"A"
$PN"1"82;
%"GND"
"1","(-1500,3450)","0","pure_quanta_power","I26";
;
SIZE"1B"
CDS_LIB"pure_quanta_power"
HDL_POWER"GND";
"A<SIZE-1..0>\NAC"11;
%"GND"
"1","(-2700,3500)","0","pure_quanta_power","I27";
;
CDS_LIB"pure_quanta_power"
SIZE"1B"
HDL_POWER"GND";
"A<SIZE-1..0>\NAC"34;
%"UNIVERSAL_POWER"
"1","(-2725,2950)","0","pure_quanta_power","I28";
;
HDL_POWER"PVDD18_S5_P0"
CDS_LIB"pure_quanta_power";
"A"35;
%"Q_CAP"
"1","(-2650,2650)","0","pure_quanta","I29";
;
LOCATION"C1508"
$SEC"1"
CDS_SEC"1"
MATERIAL"X7R"
TOLERANCE"10%"
VALUE"0.1UF"
PART_NUMBER"CH4103K1B08"
VOLTAGE"16V"
PACK_TYPE"C0402"
CDS_LIB"pure_quanta";
"B"
$PN"2"12;
"A"
$PN"1"35;
%"GND"
"1","(-2650,2475)","0","pure_quanta_power","I30";
;
SIZE"1B"
CDS_LIB"pure_quanta_power"
HDL_POWER"GND";
"A<SIZE-1..0>\NAC"12;
%"SN74AVC4T774PWR"
"1","(-3225,4075)","0","pure_quanta","I31";
;
LOCATION"U149"
$SEC"1"
CDS_SEC"1"
MATERIAL"IC"
VALUE"SN74AVC4T774PWR"
PART_NUMBER"AL04T774K00"
PART_TYPE"SMLF"
CDS_LIB"pure_quanta"
NEEDS_NO_SIZE"TRUE"
CDS_LMAN_SYM_OUTLINE"-250,450,250,-450";
"VCCA"
$PN"16"33;
"VCCB"
$PN"15"30;
"B1"
$PN"14"74;
"B2"
$PN"13"76;
"B3"
$PN"12"75;
"B4"
$PN"11"72;
"GND"
$PN"10"34;
"OE \B"
$PN"9"27;
"DIR4"
$PN"8"33;
"DIR3"
$PN"7"33;
"A4"
$PN"6"67;
"A3"
$PN"5"65;
"A2"
$PN"4"66;
"A1"
$PN"3"64;
"DIR2"
$PN"2"33;
"DIR1"
$PN"1"33;
%"UNIVERSAL_POWER"
"1","(-3750,2675)","0","pure_quanta_power","I32";
;
HDL_POWER"P3V3_STBY"
CDS_LIB"pure_quanta_power";
"A"36;
%"GND"
"1","(-2725,1350)","0","pure_quanta_power","I33";
;
SIZE"1B"
CDS_LIB"pure_quanta_power"
HDL_POWER"GND";
"A<SIZE-1..0>\NAC"37;
%"SN74AVC4T774PWR"
"1","(-3250,1925)","0","pure_quanta","I34";
;
LOCATION"U148"
$SEC"1"
CDS_SEC"1"
PART_TYPE"SMLF"
MATERIAL"IC"
PART_NUMBER"AL04T774K00"
VALUE"SN74AVC4T774PWR"
CDS_LMAN_SYM_OUTLINE"-250,450,250,-450"
CDS_LIB"pure_quanta"
NEEDS_NO_SIZE"TRUE";
"VCCA"
$PN"16"36;
"VCCB"
$PN"15"35;
"B1"
$PN"14"74;
"B2"
$PN"13"76;
"B3"
$PN"12"75;
"B4"
$PN"11"72;
"GND"
$PN"10"37;
"OE \B"
$PN"9"22;
"DIR4"
$PN"8"36;
"DIR3"
$PN"7"36;
"A4"
$PN"6"71;
"A3"
$PN"5"70;
"A2"
$PN"4"69;
"A1"
$PN"3"68;
"DIR2"
$PN"2"36;
"DIR1"
$PN"1"36;
%"Q_CAP"
"1","(-3975,4550)","0","pure_quanta","I41";
;
LOCATION"C1507"
$SEC"1"
CDS_SEC"1"
MATERIAL"X7R"
TOLERANCE"10%"
VALUE"0.1UF"
PART_NUMBER"CH4103K1B08"
VOLTAGE"16V"
PACK_TYPE"C0402"
CDS_LIB"pure_quanta";
"B"
$PN"2"13;
"A"
$PN"1"33;
%"GND"
"1","(-3975,4375)","0","pure_quanta_power","I42";
;
SIZE"1B"
CDS_LIB"pure_quanta_power"
HDL_POWER"GND";
"A<SIZE-1..0>\NAC"13;
%"Q_RES"
"1","(-5725,4075)","0","pure_quanta","I53";
;
LOCATION"R1625"
$SEC"1"
CDS_SEC"1"
VALUE"0"
CDS_LIB"pure_quanta"
WATTAGE"1/16W"
MATERIAL"CHIP"
TOLERANCE"5%"
PART_NUMBER"CS00002JB38"
PACK_TYPE"0402LF";
"B"
$PN"2"49;
"A"
$PN"1"48;
%"UNIVERSAL_POWER"
"1","(-6475,4900)","0","pure_quanta_power","I54";
;
HDL_POWER"PVDD18_S5_P0"
CDS_LIB"pure_quanta_power";
"A"38;
%"GND"
"1","(-6350,4400)","0","pure_quanta_power","I55";
;
SIZE"1B"
CDS_LIB"pure_quanta_power"
HDL_POWER"GND";
"A<SIZE-1..0>\NAC"14;
%"Q_CAP"
"1","(-6350,4625)","0","pure_quanta","I56";
;
LOCATION"C1504"
$SEC"1"
CDS_SEC"1"
MATERIAL"X7R"
TOLERANCE"10%"
VALUE"0.1UF"
PART_NUMBER"CH4103K1B08"
VOLTAGE"16V"
PACK_TYPE"C0402"
CDS_LIB"pure_quanta";
"B"
$PN"2"14;
"A"
$PN"1"38;
%"Q_CAP"
"1","(-3975,2400)","0","pure_quanta","I62";
;
LOCATION"C1506"
$SEC"1"
CDS_SEC"1"
MATERIAL"X7R"
TOLERANCE"10%"
VALUE"0.1UF"
PART_NUMBER"CH4103K1B08"
VOLTAGE"16V"
PACK_TYPE"C0402"
CDS_LIB"pure_quanta";
"B"
$PN"2"15;
"A"
$PN"1"36;
%"GND"
"1","(-3975,2225)","0","pure_quanta_power","I63";
;
SIZE"1B"
CDS_LIB"pure_quanta_power"
HDL_POWER"GND";
"A<SIZE-1..0>\NAC"15;
%"Q_CAP"
"1","(-5375,3725)","0","pure_quanta","I66";
;
LOCATION"C86"
$SEC"1"
CDS_SEC"1"
MATERIAL"EMPTY"
TOLERANCE"10%"
VALUE"0.01UF"
VOLTAGE"50V"
PACK_TYPE"C0402"
CDS_LIB"pure_quanta"
PART_NUMBER"CH31006KB18"
ROOM"BMCLESS";
"B"
$PN"2"16;
"A"
$PN"1"49;
%"GND"
"1","(-5375,3500)","0","pure_quanta_power","I67";
;
SIZE"1B"
CDS_LIB"pure_quanta_power"
HDL_POWER"GND";
"A<SIZE-1..0>\NAC"16;
%"Q_RES"
"1","(-1675,4225)","0","pure_quanta","I7";
;
LOCATION"R1633"
$SEC"1"
CDS_SEC"1"
TOLERANCE"1%"
VALUE"22"
CDS_LIB"pure_quanta"
WATTAGE"1/16W"
MATERIAL"CHIP"
PART_NUMBER"CS02202FB12"
PACK_TYPE"0402LF";
"B"
$PN"2"82;
"A"
$PN"1"74;
%"UNIVERSAL_POWER"
"1","(-6425,3725)","0","pure_quanta_power","I71";
;
HDL_POWER"PVDD18_S5_P0"
CDS_LIB"pure_quanta_power";
"A"17;
%"UNIVERSAL_POWER"
"1","(-6450,3000)","0","pure_quanta_power","I73";
;
HDL_POWER"PVDD18_S5_P0"
CDS_LIB"pure_quanta_power";
"A"39;
%"Q_CAP"
"1","(-6325,2725)","0","pure_quanta","I74";
;
LOCATION"C1505"
$SEC"1"
CDS_SEC"1"
MATERIAL"X7R"
TOLERANCE"10%"
VALUE"0.1UF"
PART_NUMBER"CH4103K1B08"
VOLTAGE"16V"
PACK_TYPE"C0402"
CDS_LIB"pure_quanta";
"B"
$PN"2"18;
"A"
$PN"1"39;
%"GND"
"1","(-6325,2500)","0","pure_quanta_power","I75";
;
SIZE"1B"
CDS_LIB"pure_quanta_power"
HDL_POWER"GND";
"A<SIZE-1..0>\NAC"18;
%"SN74AVC2T245RSWR"
"1","(-7025,4000)","2","pure_quanta","I76";
;
LOCATION"U146"
$SEC"1"
CDS_SEC"1"
PART_TYPE"SMLF"
MATERIAL"IC"
VALUE"SN74AVC2T245RSWR"
PART_NUMBER"AL02T245000"
CDS_LMAN_SYM_OUTLINE"-250,375,250,-375"
CDS_LIB"pure_quanta"
NEEDS_NO_SIZE"TRUE";
"DIR1"
$PN"10"38;
"A2"
$PN"9"44;
"A1"
$PN"8"43;
"VCCA"
$PN"7"38;
"VCCB"
$PN"6"38;
"B1"
$PN"5"48;
"B2"
$PN"4"47;
"GND"
$PN"3"40;
"OE_# \B"
$PN"2"27;
"DIR2"
$PN"1"40;
%"GND"
"1","(-7650,3575)","0","pure_quanta_power","I77";
;
SIZE"1B"
CDS_LIB"pure_quanta_power"
HDL_POWER"GND";
"A<SIZE-1..0>\NAC"40;
%"UNIVERSAL_POWER"
"1","(-7700,3125)","0","pure_quanta_power","I78";
;
HDL_POWER"P3V3_STBY"
CDS_LIB"pure_quanta_power";
"A"28;
%"Q_RES"
"1","(-1675,4125)","0","pure_quanta","I8";
;
LOCATION"R1635"
$SEC"1"
CDS_SEC"1"
TOLERANCE"1%"
VALUE"22"
CDS_LIB"pure_quanta"
WATTAGE"1/16W"
MATERIAL"CHIP"
PART_NUMBER"CS02202FB12"
PACK_TYPE"0402LF";
"B"
$PN"2"84;
"A"
$PN"1"75;
%"Q_CAP"
"1","(-7825,2800)","0","pure_quanta","I80";
;
LOCATION"C1503"
$SEC"1"
CDS_SEC"1"
MATERIAL"X7R"
TOLERANCE"10%"
VALUE"0.1UF"
PART_NUMBER"CH4103K1B08"
VOLTAGE"16V"
PACK_TYPE"C0402"
CDS_LIB"pure_quanta";
"B"
$PN"2"19;
"A"
$PN"1"28;
%"GND"
"1","(-7825,2625)","0","pure_quanta_power","I81";
;
CDS_LIB"pure_quanta_power"
SIZE"1B"
HDL_POWER"GND";
"A<SIZE-1..0>\NAC"19;
%"UNIVERSAL_POWER"
"1","(-7475,1400)","0","pure_quanta_power","I82";
;
HDL_POWER"P3V3_STBY"
CDS_LIB"pure_quanta_power";
"A"20;
%"Q_RES"
"2","(-7475,1200)","0","pure_quanta","I83";
;
LOCATION"R1622"
$SEC"1"
CDS_SEC"1"
PACK_TYPE"0402LF"
PART_NUMBER"TMP_QCS24702JB38"
VALUE"4.7K"
TOLERANCE"5%"
MATERIAL"CHIP"
WATTAGE"1/16W"
CDS_LIB"pure_quanta";
"A"
$PN"1"20;
"B"
$PN"2"22;
%"GND"
"1","(-7750,1675)","0","pure_quanta_power","I84";
;
CDS_LIB"pure_quanta_power"
SIZE"1B"
HDL_POWER"GND";
"A<SIZE-1..0>\NAC"41;
%"GND"
"1","(-7475,300)","0","pure_quanta_power","I85";
;
CDS_LIB"pure_quanta_power"
SIZE"1B"
HDL_POWER"GND";
"A<SIZE-1..0>\NAC"21;
%"Q_RES"
"1","(-1675,4075)","0","pure_quanta","I9";
;
LOCATION"R1636"
$SEC"1"
CDS_SEC"1"
TOLERANCE"1%"
VALUE"22"
CDS_LIB"pure_quanta"
WATTAGE"1/16W"
MATERIAL"CHIP"
PART_NUMBER"CS02202FB12"
PACK_TYPE"0402LF";
"B"
$PN"2"73;
"A"
$PN"1"72;
%"Q_RES"
"1","(-8325,3350)","0","pure_quanta","I92";
;
LOCATION"R1619"
$SEC"1"
CDS_SEC"1"
MATERIAL"CHIP"
VALUE"0"
CDS_LIB"pure_quanta"
WATTAGE"1/16W"
TOLERANCE"5%"
PART_NUMBER"CS00002JB38"
PACK_TYPE"0402LF";
"B"
$PN"2"27;
"A"
$PN"1"42;
%"Q_RES"
"1","(-1675,4175)","0","pure_quanta","I96";
;
LOCATION"R1634"
$SEC"1"
CDS_SEC"1"
TOLERANCE"1%"
VALUE"22"
CDS_LIB"pure_quanta"
WATTAGE"1/16W"
MATERIAL"CHIP"
PART_NUMBER"CS02202FB12"
PACK_TYPE"0402LF";
"B"
$PN"2"83;
"A"
$PN"1"76;
END.
